FILE_TYPE=LIBRARY_PARTS;
primitive '21K5R2F-GP';
  pin
    '1':
      PIN_NUMBER='(1)';
      PIN_TYPE='ANALOG';
      NO_LOAD_CHECK='Both';
      NO_IO_CHECK='Both';
      NO_ASSERT_CHECK='TRUE';
      NO_DIR_CHECK='TRUE';
      ALLOW_CONNECT='TRUE';
    '2':
      PIN_NUMBER='(2)';
      PIN_TYPE='ANALOG';
      NO_LOAD_CHECK='Both';
      NO_IO_CHECK='Both';
      NO_ASSERT_CHECK='TRUE';
      NO_DIR_CHECK='TRUE';
      ALLOW_CONNECT='TRUE';
  end_pin;
  body
    PART_NAME='21K5R2F-GP';
    BODY_NAME='21K5R2F-GP';
    PHYS_DES_PREFIX='R';
    CLASS='DISCRETE';
  end_body;
end_primitive;

END.
